# SCM (Grand Teton) — schematic netlist excerpt (pin names and nets, part order shuffled) for the footprints in the layout excerpt that follows; sources: Cadence DE-HDL packaged netlist, KiCad conversion of 12092022_DA0F0TMDCD0_F0T_Management_Board_D_brd_V3_OCP.brd

L30  Q_INDUCTOR  BLM18BB470/500MA IND  pkg SMLF  page 23 : \1\ = V_DACR ; \2\ = V_DACR_IO
R381  Q_RES  0 5% CHIP  pkg 0402LF  page 52 : A = EN_P3V3 ; B = PWRGD_EN_P3V3_R

(kicad_pcb
	(version 20260206)
	(generator "pcbnew")
	(generator_version "10.0")
	(general
		(thickness 1.6)
		(legacy_teardrops no)
	)
	(paper "A4")
	(title_block
		(title "12092022_DA0F0TMDCD0_F0T_Management_Board_D_brd_V3_OCP.brd")
		(comment 1 "Grand Teton / footprints 59-60 of 1440")
	)
	(layers
		(0 "F.Cu" signal "TOP")
		(4 "In1.Cu" signal "GND")
		(6 "In2.Cu" signal "IN1")
		(8 "In3.Cu" signal "GND1")
		(10 "In4.Cu" signal "IN2")
		(12 "In5.Cu" signal "VCC")
		(14 "In6.Cu" signal "VCC1")
		(16 "In7.Cu" signal "IN3")
		(18 "In8.Cu" signal "GND2")
		(20 "In9.Cu" signal "IN4")
		(22 "In10.Cu" signal "GND3")
		(2 "B.Cu" signal "BOTTOM")
		(9 "F.Adhes" user "F.Adhesive")
		(11 "B.Adhes" user "B.Adhesive")
		(13 "F.Paste" user "Package Geometry/Pastemask Top")
		(15 "B.Paste" user "Package Geometry/Pastemask Bottom")
		(5 "F.SilkS" user "Ref Des/Silkscreen Top")
		(7 "B.SilkS" user "Ref Des/Silkscreen Bottom")
		(1 "F.Mask" user "Board Geometry/Soldermask Top")
		(3 "B.Mask" user "Board Geometry/Soldermask Bottom")
		(17 "Dwgs.User" user "User.Drawings")
		(19 "Cmts.User" user "User.Comments")
		(21 "Eco1.User" user "User.Eco1")
		(23 "Eco2.User" user "User.Eco2")
		(25 "Edge.Cuts" user "Board Geometry/Outline")
		(27 "Margin" user)
		(31 "F.CrtYd" user "Package Geometry/Place Bound Top")
		(29 "B.CrtYd" user "Package Geometry/Place Bound Bottom")
		(35 "F.Fab" user "Ref Des/Assembly Top")
		(33 "B.Fab" user "Ref Des/Assembly Bottom")
	)
	(footprint ""
		(layer "F.Cu")
		(at 11.6586 -63.1952 180)
		(property "Reference" "R381"
			(at 0 0 180)
			(layer "F.SilkS")
			(hide yes)
			(effects
				(font
					(size 1.27 1.27)
				)
			)
		)
		(property "Value" ""
			(at 0 0 180)
			(layer "F.Fab")
			(effects
				(font
					(size 1.27 1.27)
				)
			)
		)
		(duplicate_pad_numbers_are_jumpers no)
		(fp_line
			(start 0.7874 0.4064)
			(end -0.7874 0.4064)
			(stroke
				(width 0.1524)
				(type default)
			)
			(layer "F.SilkS")
		)
		(fp_line
			(start 0.7874 -0.4064)
			(end 0.7874 0.4064)
			(stroke
				(width 0.1524)
				(type default)
			)
			(layer "F.SilkS")
		)
		(fp_line
			(start -0.7874 0.4064)
			(end -0.7874 -0.4064)
			(stroke
				(width 0.1524)
				(type default)
			)
			(layer "F.SilkS")
		)
		(fp_line
			(start -0.7874 -0.4064)
			(end 0.7874 -0.4064)
			(stroke
				(width 0.1524)
				(type default)
			)
			(layer "F.SilkS")
		)
		(fp_line
			(start 0.67945 0.3048)
			(end 0.120396 0.3048)
			(stroke
				(width 0.1)
				(type default)
			)
			(layer "F.Fab")
		)
		(fp_line
			(start 0.67945 -0.3048)
			(end 0.67945 0.3048)
			(stroke
				(width 0.1)
				(type default)
			)
			(layer "F.Fab")
		)
		(fp_line
			(start 0.12065 -0.2794)
			(end 0.12065 -0.3048)
			(stroke
				(width 0.1)
				(type default)
			)
			(layer "F.Fab")
		)
		(fp_line
			(start 0.12065 -0.3048)
			(end 0.67945 -0.3048)
			(stroke
				(width 0.1)
				(type default)
			)
			(layer "F.Fab")
		)
		(fp_line
			(start 0.120396 0.3048)
			(end 0.120396 0.2794)
			(stroke
				(width 0.1)
				(type default)
			)
			(layer "F.Fab")
		)
		(fp_line
			(start 0.120396 0.2794)
			(end -0.12065 0.2794)
			(stroke
				(width 0.1)
				(type default)
			)
			(layer "F.Fab")
		)
		(fp_line
			(start -0.12065 0.3048)
			(end -0.67945 0.3048)
			(stroke
				(width 0.1)
				(type default)
			)
			(layer "F.Fab")
		)
		(fp_line
			(start -0.12065 0.2794)
			(end -0.12065 0.3048)
			(stroke
				(width 0.1)
				(type default)
			)
			(layer "F.Fab")
		)
		(fp_line
			(start -0.12065 -0.2794)
			(end 0.12065 -0.2794)
			(stroke
				(width 0.1)
				(type default)
			)
			(layer "F.Fab")
		)
		(fp_line
			(start -0.12065 -0.305054)
			(end -0.12065 -0.2794)
			(stroke
				(width 0.1)
				(type default)
			)
			(layer "F.Fab")
		)
		(fp_line
			(start -0.67945 0.3048)
			(end -0.67945 -0.305054)
			(stroke
				(width 0.1)
				(type default)
			)
			(layer "F.Fab")
		)
		(fp_line
			(start -0.67945 -0.305054)
			(end -0.12065 -0.305054)
			(stroke
				(width 0.1)
				(type default)
			)
			(layer "F.Fab")
		)
		(pad "1" smd circle
			(at -0.40005 0 180)
			(size 0 0)
			(layers "F.Cu" "F.Mask" "F.Paste")
			(net "EN_P3V3")
		)
		(pad "2" smd circle
			(at 0.40005 0 180)
			(size 0 0)
			(layers "F.Cu" "F.Mask" "F.Paste")
			(net "PWRGD_EN_P3V3_R")
		)
	)
	(footprint ""
		(layer "F.Cu")
		(at 29.2608 -32.639)
		(property "Reference" "L30"
			(at 0 0 0)
			(layer "F.SilkS")
			(hide yes)
			(effects
				(font
					(size 1.27 1.27)
				)
			)
		)
		(property "Value" ""
			(at 0 0 0)
			(layer "F.Fab")
			(effects
				(font
					(size 1.27 1.27)
				)
			)
		)
		(duplicate_pad_numbers_are_jumpers no)
		(fp_line
			(start -1.27 -0.5842)
			(end 1.27 -0.5842)
			(stroke
				(width 0.1524)
				(type default)
			)
			(layer "F.SilkS")
		)
		(fp_line
			(start -1.27 -0.5588)
			(end -1.27 -0.5842)
			(stroke
				(width 0.1524)
				(type default)
			)
			(layer "F.SilkS")
		)
		(fp_line
			(start -1.27 0.5842)
			(end -1.27 -0.5842)
			(stroke
				(width 0.1524)
				(type default)
			)
			(layer "F.SilkS")
		)
		(fp_line
			(start -0.127 0.5842)
			(end -0.127 -0.5842)
			(stroke
				(width 0.1524)
				(type default)
			)
			(layer "F.SilkS")
		)
		(fp_line
			(start 0.127 0.5842)
			(end 0.127 -0.5842)
			(stroke
				(width 0.1524)
				(type default)
			)
			(layer "F.SilkS")
		)
		(fp_line
			(start 1.27 0.5842)
			(end -1.27 0.5842)
			(stroke
				(width 0.1524)
				(type default)
			)
			(layer "F.SilkS")
		)
		(fp_line
			(start 1.27 0.5842)
			(end 1.27 -0.5842)
			(stroke
				(width 0.1524)
				(type default)
			)
			(layer "F.SilkS")
		)
		(fp_line
			(start -1.194308 -0.406654)
			(end -0.9144 -0.406654)
			(stroke
				(width 0.1)
				(type default)
			)
			(layer "F.Fab")
		)
		(fp_line
			(start -1.194308 0.406654)
			(end -1.194308 -0.406654)
			(stroke
				(width 0.1)
				(type default)
			)
			(layer "F.Fab")
		)
		(fp_line
			(start -0.9144 -0.508)
			(end 0.9144 -0.508)
			(stroke
				(width 0.1)
				(type default)
			)
			(layer "F.Fab")
		)
		(fp_line
			(start -0.9144 -0.406654)
			(end -0.9144 -0.508)
			(stroke
				(width 0.1)
				(type default)
			)
			(layer "F.Fab")
		)
		(fp_line
			(start -0.9144 0.406654)
			(end -1.194308 0.406654)
			(stroke
				(width 0.1)
				(type default)
			)
			(layer "F.Fab")
		)
		(fp_line
			(start -0.9144 0.508)
			(end -0.9144 0.406654)
			(stroke
				(width 0.1)
				(type default)
			)
			(layer "F.Fab")
		)
		(fp_line
			(start 0.9144 -0.508)
			(end 0.9144 -0.406654)
			(stroke
				(width 0.1)
				(type default)
			)
			(layer "F.Fab")
		)
		(fp_line
			(start 0.9144 -0.406654)
			(end 1.1938 -0.406654)
			(stroke
				(width 0.1)
				(type default)
			)
			(layer "F.Fab")
		)
		(fp_line
			(start 0.9144 0.4064)
			(end 0.9144 0.508)
			(stroke
				(width 0.1)
				(type default)
			)
			(layer "F.Fab")
		)
		(fp_line
			(start 0.9144 0.508)
			(end -0.9144 0.508)
			(stroke
				(width 0.1)
				(type default)
			)
			(layer "F.Fab")
		)
		(fp_line
			(start 1.1938 -0.406654)
			(end 1.1938 0.4064)
			(stroke
				(width 0.1)
				(type default)
			)
			(layer "F.Fab")
		)
		(fp_line
			(start 1.1938 0.4064)
			(end 0.9144 0.4064)
			(stroke
				(width 0.1)
				(type default)
			)
			(layer "F.Fab")
		)
		(pad "1" smd rect
			(at -0.7366 0 270)
			(size 0.7112 0.8128)
			(layers "F.Cu" "F.Mask" "F.Paste")
			(net "V_DACR")
		)
		(pad "2" smd rect
			(at 0.7366 0 270)
			(size 0.7112 0.8128)
			(layers "F.Cu" "F.Mask" "F.Paste")
			(net "V_DACR_IO")
		)
	)
)
